(kicad_pcb
	(version 20241229)
	(generator "pcbnew")
	(generator_version "9.0")
	(general
		(thickness 1.711)
		(legacy_teardrops no)
	)
	(paper "A4")
	(title_block
		(title "Antmicro Baseboard for Jetson AGX Thor")
		(date "2026-02-18")
		(rev "1.1.0")
		(company "Antmicro Ltd")
		(comment 1 "www.antmicro.com")
		(comment 9 "footprints 246-250 of 1170")
	)
	(layers
		(0 "F.Cu" signal)
		(4 "In1.Cu" signal)
		(6 "In2.Cu" signal)
		(8 "In3.Cu" signal)
		(10 "In4.Cu" jumper)
		(12 "In5.Cu" signal)
		(14 "In6.Cu" signal)
		(16 "In7.Cu" signal)
		(18 "In8.Cu" signal)
		(2 "B.Cu" signal)
		(9 "F.Adhes" user "F.Adhesive")
		(11 "B.Adhes" user "B.Adhesive")
		(13 "F.Paste" user)
		(15 "B.Paste" user)
		(5 "F.SilkS" user "F.Silkscreen")
		(7 "B.SilkS" user "B.Silkscreen")
		(1 "F.Mask" user)
		(3 "B.Mask" user)
		(17 "Dwgs.User" user "User.Drawings")
		(19 "Cmts.User" user "User.Comments")
		(21 "Eco1.User" user "User.Eco1")
		(23 "Eco2.User" user "User.Eco2")
		(25 "Edge.Cuts" user)
		(27 "Margin" user)
		(31 "F.CrtYd" user "F.Courtyard")
		(29 "B.CrtYd" user "B.Courtyard")
		(35 "F.Fab" user)
		(33 "B.Fab" user)
	)
	(footprint "antmicro-footprints:R_0402_1005Metric"
		(layer "F.Cu")
		(at 170.304468 133.12 90)
		(descr "Resistor SMD 0402")
		(tags "resistor SMD 0402")
		(property "Reference" "R369"
			(at -1.28 3.495532 90)
			(layer "F.SilkS")
			(effects
				(font
					(size 0.7 0.7)
					(thickness 0.15)
				)
				(justify left bottom)
			)
		)
		(property "Value" "R_27R_0402"
			(at -1.011843 1.772047 90)
			(layer "F.Fab")
			(effects
				(font
					(size 0.7 0.7)
					(thickness 0.15)
				)
				(justify left bottom)
			)
		)
		(property "Datasheet" "https://www.bourns.com/docs/product-datasheets/cr.pdf"
			(at 0 0 90)
			(layer "F.Fab")
			(hide yes)
			(effects
				(font
					(size 1.27 1.27)
					(thickness 0.15)
				)
			)
		)
		(property "Description" "SMD Chip Resistor, 27 ohm, ± 1%, 63 mW, 0402 [1005 Metric], Thick Film, General Purpose"
			(at 0 0 90)
			(layer "F.Fab")
			(hide yes)
			(effects
				(font
					(size 1.27 1.27)
					(thickness 0.15)
				)
			)
		)
		(property "Manufacturer" "Bourns"
			(at 0 0 90)
			(unlocked yes)
			(layer "F.Fab")
			(hide yes)
			(effects
				(font
					(size 1 1)
					(thickness 0.15)
				)
			)
		)
		(property "MPN" "CR0402-FX-27R0GLF"
			(at 0 0 90)
			(unlocked yes)
			(layer "F.Fab")
			(hide yes)
			(effects
				(font
					(size 1 1)
					(thickness 0.15)
				)
			)
		)
		(property "Val" "27R"
			(at 0 0 90)
			(unlocked yes)
			(layer "F.Fab")
			(hide yes)
			(effects
				(font
					(size 1 1)
					(thickness 0.15)
				)
			)
		)
		(property "License" "Apache-2.0"
			(at 0 0 90)
			(unlocked yes)
			(layer "F.Fab")
			(hide yes)
			(effects
				(font
					(size 1 1)
					(thickness 0.15)
				)
			)
		)
		(property "Author" "Antmicro"
			(at 0 0 90)
			(unlocked yes)
			(layer "F.Fab")
			(hide yes)
			(effects
				(font
					(size 1 1)
					(thickness 0.15)
				)
			)
		)
		(property "Tolerance" "1%"
			(at 0 0 90)
			(unlocked yes)
			(layer "F.Fab")
			(hide yes)
			(effects
				(font
					(size 1 1)
					(thickness 0.15)
				)
			)
		)
		(sheetname "/DCDC/")
		(sheetfile "dcdc.kicad_sch")
		(attr smd)
		(fp_rect
			(start -0.925 -0.47)
			(end 0.925 0.47)
			(stroke
				(width 0.05)
				(type default)
			)
			(fill no)
			(layer "F.CrtYd")
		)
		(fp_rect
			(start -0.5 -0.25)
			(end 0.5 0.25)
			(stroke
				(width 0.15)
				(type solid)
			)
			(fill no)
			(layer "F.Fab")
		)
		(fp_text user "License: Apache-2.0"
			(at -0.95 5.169 90)
			(layer "F.Fab")
			(effects
				(font
					(size 0.7 0.7)
					(thickness 0.15)
				)
				(justify left bottom)
			)
		)
		(fp_text user "Author: Antmicro"
			(at -0.95 4.169 90)
			(layer "F.Fab")
			(effects
				(font
					(size 0.7 0.7)
					(thickness 0.15)
				)
				(justify left bottom)
			)
		)
		(fp_text user "${REFERENCE}"
			(at -0.95 3.168 90)
			(layer "F.Fab")
			(effects
				(font
					(size 0.7 0.7)
					(thickness 0.15)
				)
				(justify left bottom)
			)
		)
		(pad "1" smd roundrect
			(at -0.48 0 90)
			(size 0.59 0.64)
			(layers "F.Cu" "F.Mask" "F.Paste")
			(roundrect_rratio 0.25)
			(net 1162 "Net-(U60-IN-)")
			(pintype "passive")
		)
		(pad "2" smd roundrect
			(at 0.48 0 90)
			(size 0.59 0.64)
			(layers "F.Cu" "F.Mask" "F.Paste")
			(roundrect_rratio 0.25)
			(net 2 "+3V3")
			(pintype "passive")
		)
	)
	(footprint "antmicro-footprints:R_0402_1005Metric"
		(layer "F.Cu")
		(at 183.2 107)
		(descr "Resistor SMD 0402")
		(tags "resistor SMD 0402")
		(property "Reference" "R53"
			(at 0.92 0.48 0)
			(layer "F.SilkS")
			(effects
				(font
					(size 0.7 0.7)
					(thickness 0.15)
				)
				(justify left bottom)
			)
		)
		(property "Value" "R_10k_0402"
			(at -1.011843 1.772047 0)
			(layer "F.Fab")
			(effects
				(font
					(size 0.7 0.7)
					(thickness 0.15)
				)
				(justify left bottom)
			)
		)
		(property "Datasheet" "https://www.bourns.com/docs/product-datasheets/cr.pdf"
			(at 0 0 0)
			(layer "F.Fab")
			(hide yes)
			(effects
				(font
					(size 1.27 1.27)
					(thickness 0.15)
				)
			)
		)
		(property "Description" "SMD Chip Resistor, 10 kohm, ± 1%, 62.5 mW, 0402 [1005 Metric], Thick Film, General Purpose"
			(at 0 0 0)
			(layer "F.Fab")
			(hide yes)
			(effects
				(font
					(size 1.27 1.27)
					(thickness 0.15)
				)
			)
		)
		(property "MPN" "CR0402-FX-1002GLF"
			(at 0 0 0)
			(unlocked yes)
			(layer "F.Fab")
			(hide yes)
			(effects
				(font
					(size 1 1)
					(thickness 0.15)
				)
			)
		)
		(property "Manufacturer" "Bourns"
			(at 0 0 0)
			(unlocked yes)
			(layer "F.Fab")
			(hide yes)
			(effects
				(font
					(size 1 1)
					(thickness 0.15)
				)
			)
		)
		(property "License" "Apache-2.0"
			(at 0 0 0)
			(unlocked yes)
			(layer "F.Fab")
			(hide yes)
			(effects
				(font
					(size 1 1)
					(thickness 0.15)
				)
			)
		)
		(property "Author" "Antmicro"
			(at 0 0 0)
			(unlocked yes)
			(layer "F.Fab")
			(hide yes)
			(effects
				(font
					(size 1 1)
					(thickness 0.15)
				)
			)
		)
		(property "Val" "10k"
			(at 0 0 0)
			(unlocked yes)
			(layer "F.Fab")
			(hide yes)
			(effects
				(font
					(size 1 1)
					(thickness 0.15)
				)
			)
		)
		(property "Tolerance" "1%"
			(at 0 0 0)
			(unlocked yes)
			(layer "F.Fab")
			(hide yes)
			(effects
				(font
					(size 1 1)
					(thickness 0.15)
				)
			)
		)
		(sheetname "/DCDC/")
		(sheetfile "dcdc.kicad_sch")
		(attr smd)
		(fp_rect
			(start -0.925 -0.47)
			(end 0.925 0.47)
			(stroke
				(width 0.05)
				(type default)
			)
			(fill no)
			(layer "F.CrtYd")
		)
		(fp_rect
			(start -0.5 -0.25)
			(end 0.5 0.25)
			(stroke
				(width 0.15)
				(type solid)
			)
			(fill no)
			(layer "F.Fab")
		)
		(fp_text user "Author: Antmicro"
			(at -0.95 4.169 0)
			(layer "F.Fab")
			(effects
				(font
					(size 0.7 0.7)
					(thickness 0.15)
				)
				(justify left bottom)
			)
		)
		(fp_text user "License: Apache-2.0"
			(at -0.95 5.169 0)
			(layer "F.Fab")
			(effects
				(font
					(size 0.7 0.7)
					(thickness 0.15)
				)
				(justify left bottom)
			)
		)
		(fp_text user "${REFERENCE}"
			(at -0.95 3.168 0)
			(layer "F.Fab")
			(effects
				(font
					(size 0.7 0.7)
					(thickness 0.15)
				)
				(justify left bottom)
			)
		)
		(pad "1" smd roundrect
			(at -0.48 0)
			(size 0.59 0.64)
			(layers "F.Cu" "F.Mask" "F.Paste")
			(roundrect_rratio 0.25)
			(net 1 "GND")
			(pintype "passive")
		)
		(pad "2" smd roundrect
			(at 0.48 0)
			(size 0.59 0.64)
			(layers "F.Cu" "F.Mask" "F.Paste")
			(roundrect_rratio 0.25)
			(net 1217 "/DCDC/5V_FB")
			(pintype "passive")
		)
	)
	(footprint "antmicro-footprints:C_0805_2012Metric"
		(layer "F.Cu")
		(at 171.35 89.11 90)
		(descr "Capacitor SMD 0805")
		(tags "capacitor SMD 0805")
		(property "Reference" "C241"
			(at -1.69 -4.74 90)
			(layer "F.SilkS")
			(effects
				(font
					(size 0.7 0.7)
					(thickness 0.15)
				)
				(justify left bottom)
			)
		)
		(property "Value" "C_22u_25V_0805"
			(at -2.055717 1.963152 90)
			(layer "F.Fab")
			(effects
				(font
					(size 0.7 0.7)
					(thickness 0.15)
				)
				(justify left bottom)
			)
		)
		(property "Datasheet" "https://product.samsungsem.com/mlcc/CL21A226MAYNNN.do"
			(at 0 0 90)
			(layer "F.Fab")
			(hide yes)
			(effects
				(font
					(size 1.27 1.27)
					(thickness 0.15)
				)
			)
		)
		(property "Description" "SMT Multilayer Ceramic Capacitor, 22uF, +/-20%, 25V, X5R, 0805 [2012 Metric]"
			(at 0 0 90)
			(layer "F.Fab")
			(hide yes)
			(effects
				(font
					(size 1.27 1.27)
					(thickness 0.15)
				)
			)
		)
		(property "MPN" "CL21A226MAYNNNE"
			(at 0 0 90)
			(unlocked yes)
			(layer "F.Fab")
			(hide yes)
			(effects
				(font
					(size 1 1)
					(thickness 0.15)
				)
			)
		)
		(property "Manufacturer" "Samsung Electro-Mechanics"
			(at 0 0 90)
			(unlocked yes)
			(layer "F.Fab")
			(hide yes)
			(effects
				(font
					(size 1 1)
					(thickness 0.15)
				)
			)
		)
		(property "License" "Apache-2.0"
			(at 0 0 90)
			(unlocked yes)
			(layer "F.Fab")
			(hide yes)
			(effects
				(font
					(size 1 1)
					(thickness 0.15)
				)
			)
		)
		(property "Author" "Antmicro"
			(at 0 0 90)
			(unlocked yes)
			(layer "F.Fab")
			(hide yes)
			(effects
				(font
					(size 1 1)
					(thickness 0.15)
				)
			)
		)
		(property "Val" "22u"
			(at 0 0 90)
			(unlocked yes)
			(layer "F.Fab")
			(hide yes)
			(effects
				(font
					(size 1 1)
					(thickness 0.15)
				)
			)
		)
		(property "Voltage" "25V"
			(at 0 0 90)
			(unlocked yes)
			(layer "F.Fab")
			(hide yes)
			(effects
				(font
					(size 1 1)
					(thickness 0.15)
				)
			)
		)
		(property "Dielectric" "X5R"
			(at 0 0 90)
			(unlocked yes)
			(layer "F.Fab")
			(hide yes)
			(effects
				(font
					(size 1 1)
					(thickness 0.15)
				)
			)
		)
		(property "Public" "False"
			(at 0 0 90)
			(unlocked yes)
			(layer "F.Fab")
			(hide yes)
			(effects
				(font
					(size 1 1)
					(thickness 0.15)
				)
			)
		)
		(component_classes
			(class "DCDC_SOM")
		)
		(sheetname "/DCDC/")
		(sheetfile "dcdc.kicad_sch")
		(attr smd)
		(fp_line
			(start -0.3 -0.7)
			(end 0.3 -0.7)
			(stroke
				(width 0.15)
				(type solid)
			)
			(layer "F.SilkS")
		)
		(fp_line
			(start -0.3 0.7)
			(end 0.3 0.7)
			(stroke
				(width 0.15)
				(type solid)
			)
			(layer "F.SilkS")
		)
		(fp_rect
			(start 1.95 -0.9)
			(end -1.95 0.9)
			(stroke
				(width 0.05)
				(type default)
			)
			(fill no)
			(layer "F.CrtYd")
		)
		(fp_rect
			(start -0.95 -0.675)
			(end 0.95 0.675)
			(stroke
				(width 0.15)
				(type solid)
			)
			(fill no)
			(layer "F.Fab")
		)
		(fp_text user "Author: Antmicro"
			(at -1.9 5.947 90)
			(layer "F.Fab")
			(effects
				(font
					(size 0.7 0.7)
					(thickness 0.15)
				)
				(justify left bottom)
			)
		)
		(fp_text user "License: Apache-2.0"
			(at -1.9 4.947 90)
			(layer "F.Fab")
			(effects
				(font
					(size 0.7 0.7)
					(thickness 0.15)
				)
				(justify left bottom)
			)
		)
		(fp_text user "${REFERENCE}"
			(at -1.9 3.947 90)
			(layer "F.Fab")
			(effects
				(font
					(size 0.7 0.7)
					(thickness 0.15)
				)
				(justify left bottom)
			)
		)
		(pad "1" smd roundrect
			(at -1.1 0 90)
			(size 1.2 1.3)
			(layers "F.Cu" "F.Mask" "F.Paste")
			(roundrect_rratio 0.25)
			(net 1 "GND")
			(pintype "passive")
		)
		(pad "2" smd roundrect
			(at 1.1 0 90)
			(size 1.2 1.3)
			(layers "F.Cu" "F.Mask" "F.Paste")
			(roundrect_rratio 0.25)
			(net 13 "VCC")
			(pintype "passive")
		)
	)
	(footprint "antmicro-footprints:C_0402_1005Metric"
		(layer "F.Cu")
		(at 176.63 70.39 -90)
		(descr "Capacitor SMD 0402")
		(tags "capacitor SMD 0402")
		(property "Reference" "C278"
			(at -3.64 0.35 90)
			(layer "F.SilkS")
			(effects
				(font
					(size 0.7 0.7)
					(thickness 0.15)
				)
				(justify right top)
			)
		)
		(property "Value" "C_100n_0402"
			(at -1.022927 2.155213 90)
			(layer "F.Fab")
			(effects
				(font
					(size 0.7 0.7)
					(thickness 0.15)
				)
				(justify right top)
			)
		)
		(property "Datasheet" "https://www.murata.com/products/productdetail?partno=GRM155R61H104KE14%23"
			(at 0 0 90)
			(layer "F.Fab")
			(hide yes)
			(effects
				(font
					(size 1.27 1.27)
					(thickness 0.15)
				)
			)
		)
		(property "Description" "SMD Multilayer Ceramic Capacitor, 0.1 µF, 50 V, 0402 [1005 Metric], ± 10%, X5R, GRM Series"
			(at 0 0 90)
			(layer "F.Fab")
			(hide yes)
			(effects
				(font
					(size 1.27 1.27)
					(thickness 0.15)
				)
			)
		)
		(property "Manufacturer" "Murata"
			(at 0 0 270)
			(unlocked yes)
			(layer "F.Fab")
			(hide yes)
			(effects
				(font
					(size 1 1)
					(thickness 0.15)
				)
			)
		)
		(property "MPN" "GRM155R61H104KE14D"
			(at 0 0 270)
			(unlocked yes)
			(layer "F.Fab")
			(hide yes)
			(effects
				(font
					(size 1 1)
					(thickness 0.15)
				)
			)
		)
		(property "Val" "100n"
			(at 0 0 270)
			(unlocked yes)
			(layer "F.Fab")
			(hide yes)
			(effects
				(font
					(size 1 1)
					(thickness 0.15)
				)
			)
		)
		(property "License" "Apache-2.0"
			(at 0 0 270)
			(unlocked yes)
			(layer "F.Fab")
			(hide yes)
			(effects
				(font
					(size 1 1)
					(thickness 0.15)
				)
			)
		)
		(property "Author" "Antmicro"
			(at 0 0 270)
			(unlocked yes)
			(layer "F.Fab")
			(hide yes)
			(effects
				(font
					(size 1 1)
					(thickness 0.15)
				)
			)
		)
		(property "Voltage" "50V"
			(at 0 0 270)
			(unlocked yes)
			(layer "F.Fab")
			(hide yes)
			(effects
				(font
					(size 1 1)
					(thickness 0.15)
				)
			)
		)
		(property "Dielectric" "X5R"
			(at 0 0 270)
			(unlocked yes)
			(layer "F.Fab")
			(hide yes)
			(effects
				(font
					(size 1 1)
					(thickness 0.15)
				)
			)
		)
		(component_classes
			(class "DCDC_20V")
		)
		(sheetname "/DCDC/")
		(sheetfile "dcdc.kicad_sch")
		(attr smd)
		(fp_rect
			(start -0.925 -0.47)
			(end 0.925 0.47)
			(stroke
				(width 0.05)
				(type default)
			)
			(fill no)
			(layer "F.CrtYd")
		)
		(fp_line
			(start -0.494 0.248)
			(end -0.494 -0.25)
			(stroke
				(width 0.15)
				(type solid)
			)
			(layer "F.Fab")
		)
		(fp_line
			(start 0.504 0.248)
			(end -0.494 0.248)
			(stroke
				(width 0.15)
				(type solid)
			)
			(layer "F.Fab")
		)
		(fp_line
			(start -0.494 -0.25)
			(end 0.504 -0.25)
			(stroke
				(width 0.15)
				(type solid)
			)
			(layer "F.Fab")
		)
		(fp_line
			(start 0.504 -0.25)
			(end 0.504 0.248)
			(stroke
				(width 0.15)
				(type solid)
			)
			(layer "F.Fab")
		)
		(fp_text user "Author: Antmicro"
			(at -0.939 3.399 90)
			(layer "F.Fab")
			(effects
				(font
					(size 0.7 0.7)
					(thickness 0.15)
				)
				(justify right top)
			)
		)
		(fp_text user "${REFERENCE}"
			(at -0.939 4.599 90)
			(layer "F.Fab")
			(effects
				(font
					(size 0.7 0.7)
					(thickness 0.15)
				)
				(justify right top)
			)
		)
		(fp_text user "License: Apache-2.0"
			(at -0.939 5.799 90)
			(layer "F.Fab")
			(effects
				(font
					(size 0.7 0.7)
					(thickness 0.15)
				)
				(justify right top)
			)
		)
		(pad "1" smd roundrect
			(at -0.48 0 270)
			(size 0.59 0.64)
			(layers "F.Cu" "F.Mask" "F.Paste")
			(roundrect_rratio 0.25)
			(net 13 "VCC")
			(pintype "passive")
		)
		(pad "2" smd roundrect
			(at 0.48 0 270)
			(size 0.59 0.64)
			(layers "F.Cu" "F.Mask" "F.Paste")
			(roundrect_rratio 0.25)
			(net 1 "GND")
			(pintype "passive")
		)
	)
	(footprint "antmicro-footprints:R_0402_1005Metric"
		(layer "F.Cu")
		(at 213.805 95.4 -90)
		(descr "Resistor SMD 0402")
		(tags "resistor SMD 0402")
		(property "Reference" "R116"
			(at -1.6 -1.595 90)
			(layer "F.SilkS")
			(effects
				(font
					(size 0.7 0.7)
					(thickness 0.15)
				)
				(justify right top)
			)
		)
		(property "Value" "R_100k_0402"
			(at -1.011843 1.772047 90)
			(layer "F.Fab")
			(effects
				(font
					(size 0.7 0.7)
					(thickness 0.15)
				)
				(justify right top)
			)
		)
		(property "Datasheet" "https://www.bourns.com/docs/product-datasheets/cr.pdf"
			(at 0 0 90)
			(layer "F.Fab")
			(hide yes)
			(effects
				(font
					(size 1.27 1.27)
					(thickness 0.15)
				)
			)
		)
		(property "Description" "SMD Chip Resistor, 100 kohm, ± 1%, 62.5 mW, 0402 [1005 Metric], Thick Film, General Purpose"
			(at 0 0 90)
			(layer "F.Fab")
			(hide yes)
			(effects
				(font
					(size 1.27 1.27)
					(thickness 0.15)
				)
			)
		)
		(property "Manufacturer" "Bourns"
			(at 0 0 270)
			(unlocked yes)
			(layer "F.Fab")
			(hide yes)
			(effects
				(font
					(size 1 1)
					(thickness 0.15)
				)
			)
		)
		(property "MPN" "CR0402-FX-1003GLF"
			(at 0 0 270)
			(unlocked yes)
			(layer "F.Fab")
			(hide yes)
			(effects
				(font
					(size 1 1)
					(thickness 0.15)
				)
			)
		)
		(property "Val" "100k"
			(at 0 0 270)
			(unlocked yes)
			(layer "F.Fab")
			(hide yes)
			(effects
				(font
					(size 1 1)
					(thickness 0.15)
				)
			)
		)
		(property "License" "Apache-2.0"
			(at 0 0 270)
			(unlocked yes)
			(layer "F.Fab")
			(hide yes)
			(effects
				(font
					(size 1 1)
					(thickness 0.15)
				)
			)
		)
		(property "Author" "Antmicro"
			(at 0 0 270)
			(unlocked yes)
			(layer "F.Fab")
			(hide yes)
			(effects
				(font
					(size 1 1)
					(thickness 0.15)
				)
			)
		)
		(property "Tolerance" "1%"
			(at 0 0 270)
			(unlocked yes)
			(layer "F.Fab")
			(hide yes)
			(effects
				(font
					(size 1 1)
					(thickness 0.15)
				)
			)
		)
		(sheetname "/USB DP Alt mode/")
		(sheetfile "usb_dp.kicad_sch")
		(attr smd)
		(fp_rect
			(start -0.925 -0.47)
			(end 0.925 0.47)
			(stroke
				(width 0.05)
				(type default)
			)
			(fill no)
			(layer "F.CrtYd")
		)
		(fp_rect
			(start -0.5 -0.25)
			(end 0.5 0.25)
			(stroke
				(width 0.15)
				(type solid)
			)
			(fill no)
			(layer "F.Fab")
		)
		(fp_text user "License: Apache-2.0"
			(at -0.95 5.169 90)
			(layer "F.Fab")
			(effects
				(font
					(size 0.7 0.7)
					(thickness 0.15)
				)
				(justify right top)
			)
		)
		(fp_text user "${REFERENCE}"
			(at -0.95 3.168 90)
			(layer "F.Fab")
			(effects
				(font
					(size 0.7 0.7)
					(thickness 0.15)
				)
				(justify right top)
			)
		)
		(fp_text user "Author: Antmicro"
			(at -0.95 4.169 90)
			(layer "F.Fab")
			(effects
				(font
					(size 0.7 0.7)
					(thickness 0.15)
				)
				(justify right top)
			)
		)
		(pad "1" smd roundrect
			(at -0.48 0 270)
			(size 0.59 0.64)
			(layers "F.Cu" "F.Mask" "F.Paste")
			(roundrect_rratio 0.25)
			(net 607 "/SoM_IO2/DP0.AUX-")
			(pintype "passive")
		)
		(pad "2" smd roundrect
			(at 0.48 0 270)
			(size 0.59 0.64)
			(layers "F.Cu" "F.Mask" "F.Paste")
			(roundrect_rratio 0.25)
			(net 2 "+3V3")
			(pintype "passive")
		)
	)
)
